(kicad_pcb
	(version 20241229)
	(generator "pcbnew")
	(generator_version "9.0")
	(general
		(thickness 1.63)
		(legacy_teardrops no)
	)
	(paper "A4")
	(title_block
		(title "CM4 Baseboard")
		(date "2026-01-05")
		(rev "1.1.1")
		(company "Antmicro Ltd")
		(comment 1 "www.antmicro.com")
		(comment 9 "footprints 148-150 of 506")
	)
	(layers
		(0 "F.Cu" signal)
		(4 "In1.Cu" power)
		(6 "In2.Cu" power)
		(8 "In3.Cu" signal)
		(10 "In4.Cu" signal)
		(2 "B.Cu" signal)
		(9 "F.Adhes" user "F.Adhesive")
		(11 "B.Adhes" user "B.Adhesive")
		(13 "F.Paste" user)
		(15 "B.Paste" user)
		(5 "F.SilkS" user "F.Silkscreen")
		(7 "B.SilkS" user "B.Silkscreen")
		(1 "F.Mask" user)
		(3 "B.Mask" user)
		(17 "Dwgs.User" user "User.Drawings")
		(19 "Cmts.User" user "User.Comments")
		(21 "Eco1.User" user "User.Eco1")
		(23 "Eco2.User" user "User.Eco2")
		(25 "Edge.Cuts" user)
		(27 "Margin" user)
		(31 "F.CrtYd" user "F.Courtyard")
		(29 "B.CrtYd" user "B.Courtyard")
		(35 "F.Fab" user)
		(33 "B.Fab" user)
	)
	(footprint "antmicro-footprints:SW_KMR211NGLFS_SMD"
		(layer "F.Cu")
		(at 130.517962 122.8665 -90)
		(property "Reference" "S202"
			(at 3.6335 1.542962 0)
			(layer "F.SilkS")
			(effects
				(font
					(size 0.7 0.7)
					(thickness 0.15)
				)
				(justify left bottom)
			)
		)
		(property "Value" "SW_KMR211NGLFS_SMD"
			(at 0 2.8 90)
			(layer "F.Fab")
			(effects
				(font
					(size 0.7 0.7)
					(thickness 0.15)
				)
				(justify right bottom)
			)
		)
		(property "Datasheet" "http://www.farnell.com/datasheets/2631211.pdf"
			(at 0 0 270)
			(layer "F.Fab")
			(hide yes)
			(effects
				(font
					(size 1.27 1.27)
					(thickness 0.15)
				)
			)
		)
		(property "MPN" "KMR211NGLFS"
			(at 0 0 270)
			(unlocked yes)
			(layer "F.Fab")
			(hide yes)
			(effects
				(font
					(size 1 1)
					(thickness 0.15)
				)
			)
		)
		(property "Manufacturer" "C&K"
			(at 0 0 270)
			(unlocked yes)
			(layer "F.Fab")
			(hide yes)
			(effects
				(font
					(size 1 1)
					(thickness 0.15)
				)
			)
		)
		(property "Author" "Antmicro"
			(at 0 0 270)
			(unlocked yes)
			(layer "F.Fab")
			(hide yes)
			(effects
				(font
					(size 1 1)
					(thickness 0.15)
				)
			)
		)
		(property "License" "Apache-2.0"
			(at 0 0 270)
			(unlocked yes)
			(layer "F.Fab")
			(hide yes)
			(effects
				(font
					(size 1 1)
					(thickness 0.15)
				)
			)
		)
		(sheetname "/Compute module/")
		(sheetfile "compute-module.kicad_sch")
		(attr smd)
		(fp_line
			(start -2.1 1.601)
			(end -2.1 1.48)
			(stroke
				(width 0.15)
				(type solid)
			)
			(layer "F.SilkS")
		)
		(fp_line
			(start 2.101 1.601)
			(end -2.1 1.601)
			(stroke
				(width 0.15)
				(type solid)
			)
			(layer "F.SilkS")
		)
		(fp_line
			(start 2.101 1.601)
			(end 2.101 1.48)
			(stroke
				(width 0.15)
				(type solid)
			)
			(layer "F.SilkS")
		)
		(fp_line
			(start 2.101 -1.58)
			(end 2.101 -1.459)
			(stroke
				(width 0.15)
				(type solid)
			)
			(layer "F.SilkS")
		)
		(fp_line
			(start -2.1 -1.6)
			(end -2.1 -1.499)
			(stroke
				(width 0.15)
				(type solid)
			)
			(layer "F.SilkS")
		)
		(fp_line
			(start 2.101 -1.6)
			(end -2.1 -1.6)
			(stroke
				(width 0.15)
				(type solid)
			)
			(layer "F.SilkS")
		)
		(fp_rect
			(start 2.751 1.75)
			(end -2.748 -1.749)
			(stroke
				(width 0.05)
				(type solid)
			)
			(fill no)
			(layer "F.CrtYd")
		)
		(fp_line
			(start -2.1 1.601)
			(end 2.101 1.601)
			(stroke
				(width 0.15)
				(type solid)
			)
			(layer "F.Fab")
		)
		(fp_line
			(start 2.101 1.601)
			(end 2.101 -1.6)
			(stroke
				(width 0.15)
				(type solid)
			)
			(layer "F.Fab")
		)
		(fp_line
			(start 0.25 0.802)
			(end -0.248 0.802)
			(stroke
				(width 0.15)
				(type solid)
			)
			(layer "F.Fab")
		)
		(fp_line
			(start -0.248 -0.8)
			(end 0.25 -0.8)
			(stroke
				(width 0.15)
				(type solid)
			)
			(layer "F.Fab")
		)
		(fp_line
			(start -2.1 -1.6)
			(end -2.1 1.601)
			(stroke
				(width 0.15)
				(type solid)
			)
			(layer "F.Fab")
		)
		(fp_line
			(start 2.101 -1.6)
			(end -2.1 -1.6)
			(stroke
				(width 0.15)
				(type solid)
			)
			(layer "F.Fab")
		)
		(fp_arc
			(start -0.248 0.802)
			(mid -1.050001 0.001)
			(end -0.248 -0.8)
			(stroke
				(width 0.15)
				(type solid)
			)
			(layer "F.Fab")
		)
		(fp_arc
			(start 0.25 -0.8)
			(mid 1.051001 0.001)
			(end 0.25 0.802)
			(stroke
				(width 0.15)
				(type solid)
			)
			(layer "F.Fab")
		)
		(fp_text user "${REFERENCE}"
			(at -3 4.25 270)
			(layer "F.Fab")
			(effects
				(font
					(size 0.7 0.7)
					(thickness 0.15)
				)
				(justify left bottom)
			)
		)
		(fp_text user "License: Apache-2.0"
			(at -3 6.75 270)
			(layer "F.Fab")
			(effects
				(font
					(size 0.7 0.7)
					(thickness 0.15)
				)
				(justify left bottom)
			)
		)
		(fp_text user "Author: Antmicro"
			(at -3 5.5 270)
			(layer "F.Fab")
			(effects
				(font
					(size 0.7 0.7)
					(thickness 0.15)
				)
				(justify left bottom)
			)
		)
		(pad "1" smd rect
			(at -2.048 -0.8 90)
			(size 0.9 1)
			(layers "F.Cu" "F.Mask" "F.Paste")
			(net 9 "+3V3")
			(pinfunction "1")
			(pintype "passive")
		)
		(pad "2" smd rect
			(at 2.05 -0.8 90)
			(size 0.9 1)
			(layers "F.Cu" "F.Mask" "F.Paste")
			(net 9 "+3V3")
			(pinfunction "2")
			(pintype "passive")
		)
		(pad "3" smd rect
			(at -2.048 0.802 90)
			(size 0.9 1)
			(layers "F.Cu" "F.Mask" "F.Paste")
			(net 4 "Net-(D204-A)")
			(pinfunction "3")
			(pintype "passive")
		)
		(pad "4" smd rect
			(at 2.05 0.802 90)
			(size 0.9 1)
			(layers "F.Cu" "F.Mask" "F.Paste")
			(net 4 "Net-(D204-A)")
			(pinfunction "4")
			(pintype "passive")
		)
	)
	(footprint "antmicro-footprints:Spacer_Drill3.7mm_H3mm_9774030151R"
		(layer "F.Cu")
		(at 113.520961 176.314 90)
		(descr "Spacer M=3 h=3mm fi=5.1mm")
		(property "Reference" "H201"
			(at 0 -3.2 90)
			(layer "F.SilkS")
			(hide yes)
			(effects
				(font
					(size 0.7 0.7)
					(thickness 0.15)
				)
				(justify left bottom)
			)
		)
		(property "Value" "Spacer_Drill3.7mm_H3mm_9774030151R"
			(at 0 4 90)
			(layer "F.Fab")
			(effects
				(font
					(size 0.7 0.7)
					(thickness 0.15)
				)
				(justify left bottom)
			)
		)
		(property "Datasheet" "https://www.we-online.com/catalog/datasheet/9774030151.pdf"
			(at 0 0 90)
			(layer "F.Fab")
			(hide yes)
			(effects
				(font
					(size 1.27 1.27)
					(thickness 0.15)
				)
			)
		)
		(property "Manufacturer" "Würth Elektronik"
			(at 0 0 90)
			(unlocked yes)
			(layer "F.Fab")
			(hide yes)
			(effects
				(font
					(size 1 1)
					(thickness 0.15)
				)
			)
		)
		(property "MPN" "9774030151R"
			(at 0 0 90)
			(unlocked yes)
			(layer "F.Fab")
			(hide yes)
			(effects
				(font
					(size 1 1)
					(thickness 0.15)
				)
			)
		)
		(property "Author" "Antmicro"
			(at 0 0 90)
			(unlocked yes)
			(layer "F.Fab")
			(hide yes)
			(effects
				(font
					(size 1 1)
					(thickness 0.15)
				)
			)
		)
		(property "License" "Apache-2.0"
			(at 0 0 90)
			(unlocked yes)
			(layer "F.Fab")
			(hide yes)
			(effects
				(font
					(size 1 1)
					(thickness 0.15)
				)
			)
		)
		(sheetname "/Compute module/")
		(sheetfile "compute-module.kicad_sch")
		(solder_paste_margin_ratio -1)
		(attr smd)
		(fp_circle
			(center 0 0)
			(end 3.05 0)
			(stroke
				(width 0.05)
				(type solid)
			)
			(fill no)
			(layer "F.CrtYd")
		)
		(fp_circle
			(center 0 0)
			(end 2.6 0)
			(stroke
				(width 0.15)
				(type solid)
			)
			(fill no)
			(layer "F.Fab")
		)
		(fp_text user "Author: Antmicro"
			(at -9.6 7.7 90)
			(layer "F.Fab")
			(effects
				(font
					(size 0.7 0.7)
					(thickness 0.15)
				)
				(justify left bottom)
			)
		)
		(fp_text user "License: Apache-2.0"
			(at -9.6 8.9 90)
			(layer "F.Fab")
			(effects
				(font
					(size 0.7 0.7)
					(thickness 0.15)
				)
				(justify left bottom)
			)
		)
		(fp_text user "${REFERENCE}"
			(at -9.6 6.5 90)
			(layer "F.Fab")
			(effects
				(font
					(size 0.7 0.7)
					(thickness 0.15)
				)
				(justify left bottom)
			)
		)
		(pad "" smd custom
			(at -1.7 -1.7 90)
			(size 0.62 0.62)
			(layers "F.Paste")
			(thermal_bridge_angle 90)
			(options
				(clearance outline)
				(anchor circle)
			)
			(primitives
				(gr_arc
					(start -0.250195 1.279127)
					(mid 0.285453 0.294389)
					(end 1.266786 -0.24747)
					(width 0.2)
				)
				(gr_arc
					(start -0.34334 1.279127)
					(mid 0.218448 0.232561)
					(end 1.259603 -0.339191)
					(width 0.2)
				)
				(gr_arc
					(start -0.436309 1.279127)
					(mid 0.152481 0.169693)
					(end 1.255279 -0.431435)
					(width 0.2)
				)
				(gr_arc
					(start -0.529126 1.279127)
					(mid 0.087542 0.105784)
					(end 1.253811 -0.524161)
					(width 0.2)
				)
				(gr_arc
					(start -0.621807 1.279127)
					(mid 0.0309 0.033527)
					(end 1.275473 -0.621136)
					(width 0.2)
				)
				(gr_arc
					(start -0.71437 1.279127)
					(mid -0.037758 -0.026651)
					(end 1.263664 -0.711602)
					(width 0.2)
				)
				(gr_arc
					(start -0.806826 1.279127)
					(mid -0.105837 -0.087395)
					(end 1.253435 -0.802342)
					(width 0.2)
				)
				(gr_arc
					(start -0.899187 1.279127)
					(mid -0.165236 -0.156885)
					(end 1.267475 -0.897258)
					(width 0.2)
				)
				(gr_arc
					(start -0.991463 1.279127)
					(mid -0.228522 -0.222449)
					(end 1.270645 -0.990112)
					(width 0.2)
				)
				(gr_arc
					(start -1.083663 1.279127)
					(mid -0.294507 -0.285313)
					(end 1.266278 -1.081674)
					(width 0.2)
				)
				(gr_line
					(start 1.279127 -0.250195)
					(end 1.279127 -1.083663)
					(width 0.2)
				)
				(gr_line
					(start -0.250195 1.279127)
					(end -1.083663 1.279127)
					(width 0.2)
				)
			)
		)
		(pad "" smd custom
			(at -1.7 1.7 180)
			(size 0.62 0.62)
			(layers "F.Paste")
			(thermal_bridge_angle 90)
			(options
				(clearance outline)
				(anchor circle)
			)
			(primitives
				(gr_arc
					(start -0.250195 1.279127)
					(mid 0.285453 0.294389)
					(end 1.266786 -0.24747)
					(width 0.2)
				)
				(gr_arc
					(start -0.34334 1.279127)
					(mid 0.218448 0.232561)
					(end 1.259603 -0.339191)
					(width 0.2)
				)
				(gr_arc
					(start -0.436309 1.279127)
					(mid 0.152481 0.169693)
					(end 1.255279 -0.431435)
					(width 0.2)
				)
				(gr_arc
					(start -0.529126 1.279127)
					(mid 0.087542 0.105784)
					(end 1.253811 -0.524161)
					(width 0.2)
				)
				(gr_arc
					(start -0.621807 1.279127)
					(mid 0.0309 0.033527)
					(end 1.275473 -0.621136)
					(width 0.2)
				)
				(gr_arc
					(start -0.71437 1.279127)
					(mid -0.037758 -0.026651)
					(end 1.263664 -0.711602)
					(width 0.2)
				)
				(gr_arc
					(start -0.806826 1.279127)
					(mid -0.105837 -0.087395)
					(end 1.253435 -0.802342)
					(width 0.2)
				)
				(gr_arc
					(start -0.899187 1.279127)
					(mid -0.165236 -0.156885)
					(end 1.267475 -0.897258)
					(width 0.2)
				)
				(gr_arc
					(start -0.991463 1.279127)
					(mid -0.228522 -0.222449)
					(end 1.270645 -0.990112)
					(width 0.2)
				)
				(gr_arc
					(start -1.083663 1.279127)
					(mid -0.294507 -0.285313)
					(end 1.266278 -1.081674)
					(width 0.2)
				)
				(gr_line
					(start 1.279127 -0.250195)
					(end 1.279127 -1.083663)
					(width 0.2)
				)
				(gr_line
					(start -0.250195 1.279127)
					(end -1.083663 1.279127)
					(width 0.2)
				)
			)
		)
		(pad "" smd custom
			(at 1.7 -1.7)
			(size 0.62 0.62)
			(layers "F.Paste")
			(thermal_bridge_angle 90)
			(options
				(clearance outline)
				(anchor circle)
			)
			(primitives
				(gr_arc
					(start -0.250195 1.279127)
					(mid 0.285453 0.294389)
					(end 1.266786 -0.24747)
					(width 0.2)
				)
				(gr_arc
					(start -0.34334 1.279127)
					(mid 0.218448 0.232561)
					(end 1.259603 -0.339191)
					(width 0.2)
				)
				(gr_arc
					(start -0.436309 1.279127)
					(mid 0.152481 0.169693)
					(end 1.255279 -0.431435)
					(width 0.2)
				)
				(gr_arc
					(start -0.529126 1.279127)
					(mid 0.087542 0.105784)
					(end 1.253811 -0.524161)
					(width 0.2)
				)
				(gr_arc
					(start -0.621807 1.279127)
					(mid 0.0309 0.033527)
					(end 1.275473 -0.621136)
					(width 0.2)
				)
				(gr_arc
					(start -0.71437 1.279127)
					(mid -0.037758 -0.026651)
					(end 1.263664 -0.711602)
					(width 0.2)
				)
				(gr_arc
					(start -0.806826 1.279127)
					(mid -0.105837 -0.087395)
					(end 1.253435 -0.802342)
					(width 0.2)
				)
				(gr_arc
					(start -0.899187 1.279127)
					(mid -0.165236 -0.156885)
					(end 1.267475 -0.897258)
					(width 0.2)
				)
				(gr_arc
					(start -0.991463 1.279127)
					(mid -0.228522 -0.222449)
					(end 1.270645 -0.990112)
					(width 0.2)
				)
				(gr_arc
					(start -1.083663 1.279127)
					(mid -0.294507 -0.285313)
					(end 1.266278 -1.081674)
					(width 0.2)
				)
				(gr_line
					(start 1.279127 -0.250195)
					(end 1.279127 -1.083663)
					(width 0.2)
				)
				(gr_line
					(start -0.250195 1.279127)
					(end -1.083663 1.279127)
					(width 0.2)
				)
			)
		)
		(pad "" smd custom
			(at 1.7 1.7 270)
			(size 0.62 0.62)
			(layers "F.Paste")
			(thermal_bridge_angle 90)
			(options
				(clearance outline)
				(anchor circle)
			)
			(primitives
				(gr_arc
					(start -0.250195 1.279127)
					(mid 0.285453 0.294389)
					(end 1.266786 -0.24747)
					(width 0.2)
				)
				(gr_arc
					(start -0.34334 1.279127)
					(mid 0.218448 0.232561)
					(end 1.259603 -0.339191)
					(width 0.2)
				)
				(gr_arc
					(start -0.436309 1.279127)
					(mid 0.152481 0.169693)
					(end 1.255279 -0.431435)
					(width 0.2)
				)
				(gr_arc
					(start -0.529126 1.279127)
					(mid 0.087542 0.105784)
					(end 1.253811 -0.524161)
					(width 0.2)
				)
				(gr_arc
					(start -0.621807 1.279127)
					(mid 0.0309 0.033527)
					(end 1.275473 -0.621136)
					(width 0.2)
				)
				(gr_arc
					(start -0.71437 1.279127)
					(mid -0.037758 -0.026651)
					(end 1.263664 -0.711602)
					(width 0.2)
				)
				(gr_arc
					(start -0.806826 1.279127)
					(mid -0.105837 -0.087395)
					(end 1.253435 -0.802342)
					(width 0.2)
				)
				(gr_arc
					(start -0.899187 1.279127)
					(mid -0.165236 -0.156885)
					(end 1.267475 -0.897258)
					(width 0.2)
				)
				(gr_arc
					(start -0.991463 1.279127)
					(mid -0.228522 -0.222449)
					(end 1.270645 -0.990112)
					(width 0.2)
				)
				(gr_arc
					(start -1.083663 1.279127)
					(mid -0.294507 -0.285313)
					(end 1.266278 -1.081674)
					(width 0.2)
				)
				(gr_line
					(start 1.279127 -0.250195)
					(end 1.279127 -1.083663)
					(width 0.2)
				)
				(gr_line
					(start -0.250195 1.279127)
					(end -1.083663 1.279127)
					(width 0.2)
				)
			)
		)
		(pad "1" thru_hole circle
			(at 0 0 90)
			(size 6 6)
			(drill 3.7)
			(layers "*.Cu" "*.Mask")
			(remove_unused_layers no)
			(net 3 "GND")
			(pintype "passive")
		)
	)
	(footprint "antmicro-footprints:R_0402_1005Metric"
		(layer "F.Cu")
		(at 102.067962 142.6415)
		(descr "Resistor SMD 0402")
		(tags "resistor SMD 0402")
		(property "Reference" "R930"
			(at 0.725 0.45 0)
			(layer "F.SilkS")
			(effects
				(font
					(size 0.7 0.7)
					(thickness 0.15)
				)
				(justify left bottom)
			)
		)
		(property "Value" "R_10k_0402"
			(at -1.011843 1.772047 0)
			(layer "F.Fab")
			(effects
				(font
					(size 0.7 0.7)
					(thickness 0.15)
				)
				(justify left bottom)
			)
		)
		(property "Datasheet" "https://www.bourns.com/docs/product-datasheets/cr.pdf"
			(at 0 0 0)
			(layer "F.Fab")
			(hide yes)
			(effects
				(font
					(size 1.27 1.27)
					(thickness 0.15)
				)
			)
		)
		(property "Manufacturer" "Bourns"
			(at 0 0 0)
			(unlocked yes)
			(layer "F.Fab")
			(hide yes)
			(effects
				(font
					(size 1 1)
					(thickness 0.15)
				)
			)
		)
		(property "MPN" "CR0402-FX-1002GLF"
			(at 0 0 0)
			(unlocked yes)
			(layer "F.Fab")
			(hide yes)
			(effects
				(font
					(size 1 1)
					(thickness 0.15)
				)
			)
		)
		(property "Val" "10k"
			(at 0 0 0)
			(unlocked yes)
			(layer "F.Fab")
			(hide yes)
			(effects
				(font
					(size 1 1)
					(thickness 0.15)
				)
			)
		)
		(property "License" "Apache-2.0"
			(at 0 0 0)
			(unlocked yes)
			(layer "F.Fab")
			(hide yes)
			(effects
				(font
					(size 1 1)
					(thickness 0.15)
				)
			)
		)
		(property "Author" "Antmicro"
			(at 0 0 0)
			(unlocked yes)
			(layer "F.Fab")
			(hide yes)
			(effects
				(font
					(size 1 1)
					(thickness 0.15)
				)
			)
		)
		(property "Tolerance" "1%"
			(at 0 0 0)
			(unlocked yes)
			(layer "F.Fab")
			(hide yes)
			(effects
				(font
					(size 1 1)
					(thickness 0.15)
				)
			)
		)
		(sheetname "/USB/")
		(sheetfile "usb.kicad_sch")
		(attr smd)
		(fp_rect
			(start -0.925 -0.47)
			(end 0.925 0.47)
			(stroke
				(width 0.05)
				(type default)
			)
			(fill no)
			(layer "F.CrtYd")
		)
		(fp_rect
			(start -0.5 -0.25)
			(end 0.5 0.25)
			(stroke
				(width 0.15)
				(type solid)
			)
			(fill no)
			(layer "F.Fab")
		)
		(fp_text user "${REFERENCE}"
			(at -0.95 3.168 0)
			(layer "F.Fab")
			(effects
				(font
					(size 0.7 0.7)
					(thickness 0.15)
				)
				(justify left bottom)
			)
		)
		(fp_text user "Author: Antmicro"
			(at -0.95 4.169 0)
			(layer "F.Fab")
			(effects
				(font
					(size 0.7 0.7)
					(thickness 0.15)
				)
				(justify left bottom)
			)
		)
		(fp_text user "License: Apache-2.0"
			(at -0.95 5.169 0)
			(layer "F.Fab")
			(effects
				(font
					(size 0.7 0.7)
					(thickness 0.15)
				)
				(justify left bottom)
			)
		)
		(pad "1" smd roundrect
			(at -0.48 0)
			(size 0.59 0.64)
			(layers "F.Cu" "F.Mask" "F.Paste")
			(roundrect_rratio 0.25)
			(net 27 "/USB/USB_3V3")
			(pintype "passive")
		)
		(pad "2" smd roundrect
			(at 0.48 0)
			(size 0.59 0.64)
			(layers "F.Cu" "F.Mask" "F.Paste")
			(roundrect_rratio 0.25)
			(net 455 "Net-(Q905-D)")
			(pintype "passive")
		)
	)
)
